# S9S_MB_2U (Grand Teton) — schematic netlist excerpt (pin names and nets, part order shuffled) for the footprints in the layout excerpt that follows; sources: Cadence DE-HDL packaged netlist, KiCad conversion of 03242023_DA0F0TMBIJ0_F0T_Motherboard_J_brd_V01_OCP.brd

C245  Q_CAP  47UF 4V 20% X6S  pkg C0805  page 77 : A = PVCCIN_CPU1 ; B = GND
R491  Q_RES  4.7K 1% EMPTY  pkg 0402LF  page 190 : A = M2_SSD0_CLKREQ_EN_N ; B = GND
R3580  Q_RES  0 5% CHIP  pkg 0402LF  page 231 : A = SMB_INA230_3V3AUX_SCL_R ; B = SMB_INA230_3V3AUX_SCL

(kicad_pcb
	(version 20260206)
	(generator "pcbnew")
	(generator_version "10.0")
	(general
		(thickness 1.6)
		(legacy_teardrops no)
	)
	(paper "A4")
	(title_block
		(title "03242023_DA0F0TMBIJ0_F0T_Motherboard_J_brd_V01_OCP.brd")
		(comment 1 "Grand Teton / footprints 1383-1385 of 6105")
	)
	(layers
		(0 "F.Cu" signal "TOP")
		(4 "In1.Cu" signal "GND")
		(6 "In2.Cu" signal "IN1")
		(8 "In3.Cu" signal "GND1")
		(10 "In4.Cu" signal "IN2")
		(12 "In5.Cu" signal "GND2")
		(14 "In6.Cu" signal "IN3")
		(16 "In7.Cu" signal "GND3")
		(18 "In8.Cu" signal "VCC")
		(20 "In9.Cu" signal "VCC1")
		(22 "In10.Cu" signal "GND4")
		(24 "In11.Cu" signal "IN4")
		(26 "In12.Cu" signal "GND5")
		(28 "In13.Cu" signal "IN5")
		(30 "In14.Cu" signal "GND6")
		(32 "In15.Cu" signal "IN6")
		(34 "In16.Cu" signal "GND7")
		(2 "B.Cu" signal "BOTTOM")
		(9 "F.Adhes" user "F.Adhesive")
		(11 "B.Adhes" user "B.Adhesive")
		(13 "F.Paste" user "Package Geometry/Pastemask Top")
		(15 "B.Paste" user "Package Geometry/Pastemask Bottom")
		(5 "F.SilkS" user "Ref Des/Silkscreen Top")
		(7 "B.SilkS" user "Ref Des/Silkscreen Bottom")
		(1 "F.Mask" user "Board Geometry/Soldermask Top")
		(3 "B.Mask" user "Board Geometry/Soldermask Bottom")
		(17 "Dwgs.User" user "User.Drawings")
		(19 "Cmts.User" user "User.Comments")
		(21 "Eco1.User" user "User.Eco1")
		(23 "Eco2.User" user "User.Eco2")
		(25 "Edge.Cuts" user "Board Geometry/Outline")
		(27 "Margin" user)
		(31 "F.CrtYd" user "Package Geometry/Place Bound Top")
		(29 "B.CrtYd" user "Package Geometry/Place Bound Bottom")
		(35 "F.Fab" user "Ref Des/Assembly Top")
		(33 "B.Fab" user "Ref Des/Assembly Bottom")
	)
	(footprint ""
		(layer "F.Cu")
		(at 131.78155 -42.784522 180)
		(property "Reference" "R491"
			(at 0 0 180)
			(layer "F.SilkS")
			(hide yes)
			(effects
				(font
					(size 1.27 1.27)
				)
			)
		)
		(property "Value" ""
			(at 0 0 180)
			(layer "F.Fab")
			(effects
				(font
					(size 1.27 1.27)
				)
			)
		)
		(duplicate_pad_numbers_are_jumpers no)
		(fp_line
			(start 0.7874 0.4064)
			(end -0.7874 0.4064)
			(stroke
				(width 0.1524)
				(type default)
			)
			(layer "F.SilkS")
		)
		(fp_line
			(start 0.7874 -0.4064)
			(end 0.7874 0.4064)
			(stroke
				(width 0.1524)
				(type default)
			)
			(layer "F.SilkS")
		)
		(fp_line
			(start -0.7874 0.4064)
			(end -0.7874 -0.4064)
			(stroke
				(width 0.1524)
				(type default)
			)
			(layer "F.SilkS")
		)
		(fp_line
			(start -0.7874 -0.4064)
			(end 0.7874 -0.4064)
			(stroke
				(width 0.1524)
				(type default)
			)
			(layer "F.SilkS")
		)
		(fp_line
			(start 0.67945 0.3048)
			(end 0.120396 0.3048)
			(stroke
				(width 0.1)
				(type default)
			)
			(layer "F.Fab")
		)
		(fp_line
			(start 0.67945 -0.3048)
			(end 0.67945 0.3048)
			(stroke
				(width 0.1)
				(type default)
			)
			(layer "F.Fab")
		)
		(fp_line
			(start 0.12065 -0.2794)
			(end 0.12065 -0.3048)
			(stroke
				(width 0.1)
				(type default)
			)
			(layer "F.Fab")
		)
		(fp_line
			(start 0.12065 -0.3048)
			(end 0.67945 -0.3048)
			(stroke
				(width 0.1)
				(type default)
			)
			(layer "F.Fab")
		)
		(fp_line
			(start 0.120396 0.3048)
			(end 0.120396 0.2794)
			(stroke
				(width 0.1)
				(type default)
			)
			(layer "F.Fab")
		)
		(fp_line
			(start 0.120396 0.2794)
			(end -0.12065 0.2794)
			(stroke
				(width 0.1)
				(type default)
			)
			(layer "F.Fab")
		)
		(fp_line
			(start -0.12065 0.3048)
			(end -0.67945 0.3048)
			(stroke
				(width 0.1)
				(type default)
			)
			(layer "F.Fab")
		)
		(fp_line
			(start -0.12065 0.2794)
			(end -0.12065 0.3048)
			(stroke
				(width 0.1)
				(type default)
			)
			(layer "F.Fab")
		)
		(fp_line
			(start -0.12065 -0.2794)
			(end 0.12065 -0.2794)
			(stroke
				(width 0.1)
				(type default)
			)
			(layer "F.Fab")
		)
		(fp_line
			(start -0.12065 -0.305054)
			(end -0.12065 -0.2794)
			(stroke
				(width 0.1)
				(type default)
			)
			(layer "F.Fab")
		)
		(fp_line
			(start -0.67945 0.3048)
			(end -0.67945 -0.305054)
			(stroke
				(width 0.1)
				(type default)
			)
			(layer "F.Fab")
		)
		(fp_line
			(start -0.67945 -0.305054)
			(end -0.12065 -0.305054)
			(stroke
				(width 0.1)
				(type default)
			)
			(layer "F.Fab")
		)
		(pad "1" smd circle
			(at -0.40005 0 180)
			(size 0 0)
			(layers "F.Cu" "F.Mask" "F.Paste")
			(net "M2_SSD0_CLKREQ_EN_N")
		)
		(pad "2" smd circle
			(at 0.40005 0 180)
			(size 0 0)
			(layers "F.Cu" "F.Mask" "F.Paste")
			(net "GND")
		)
	)
	(footprint ""
		(layer "F.Cu")
		(at 118.09222 -296.05478 180)
		(property "Reference" "C245"
			(at 0 0 180)
			(layer "F.SilkS")
			(hide yes)
			(effects
				(font
					(size 1.27 1.27)
				)
			)
		)
		(property "Value" ""
			(at 0 0 180)
			(layer "F.Fab")
			(effects
				(font
					(size 1.27 1.27)
				)
			)
		)
		(duplicate_pad_numbers_are_jumpers no)
		(fp_line
			(start 1.524 0.762)
			(end -1.524 0.762)
			(stroke
				(width 0.1524)
				(type default)
			)
			(layer "F.SilkS")
		)
		(fp_line
			(start 1.524 -0.762)
			(end 1.524 0.762)
			(stroke
				(width 0.1524)
				(type default)
			)
			(layer "F.SilkS")
		)
		(fp_line
			(start -1.524 0.762)
			(end -1.524 -0.762)
			(stroke
				(width 0.1524)
				(type default)
			)
			(layer "F.SilkS")
		)
		(fp_line
			(start -1.524 -0.762)
			(end 1.524 -0.762)
			(stroke
				(width 0.1524)
				(type default)
			)
			(layer "F.SilkS")
		)
		(fp_line
			(start 1.1049 0.724916)
			(end 1.1049 -0.724916)
			(stroke
				(width 0.1)
				(type default)
			)
			(layer "F.Fab")
		)
		(fp_line
			(start 1.1049 -0.724916)
			(end -1.1049 -0.724916)
			(stroke
				(width 0.1)
				(type default)
			)
			(layer "F.Fab")
		)
		(fp_line
			(start -1.1049 0.724916)
			(end 1.1049 0.724916)
			(stroke
				(width 0.1)
				(type default)
			)
			(layer "F.Fab")
		)
		(fp_line
			(start -1.1049 -0.724916)
			(end -1.1049 0.724916)
			(stroke
				(width 0.1)
				(type default)
			)
			(layer "F.Fab")
		)
		(pad "1" smd rect
			(at -0.889 0)
			(size 1.016 1.27)
			(layers "F.Cu" "F.Mask" "F.Paste")
			(net "PVCCIN_CPU1")
		)
		(pad "2" smd rect
			(at 0.889 0)
			(size 1.016 1.27)
			(layers "F.Cu" "F.Mask" "F.Paste")
			(net "GND")
		)
	)
	(footprint ""
		(layer "F.Cu")
		(at 128.401572 -134.066026)
		(property "Reference" "R3580"
			(at 0 0 0)
			(layer "F.SilkS")
			(hide yes)
			(effects
				(font
					(size 1.27 1.27)
				)
			)
		)
		(property "Value" ""
			(at 0 0 0)
			(layer "F.Fab")
			(effects
				(font
					(size 1.27 1.27)
				)
			)
		)
		(duplicate_pad_numbers_are_jumpers no)
		(fp_line
			(start -0.7874 -0.4064)
			(end 0.7874 -0.4064)
			(stroke
				(width 0.1524)
				(type default)
			)
			(layer "F.SilkS")
		)
		(fp_line
			(start -0.7874 0.4064)
			(end -0.7874 -0.4064)
			(stroke
				(width 0.1524)
				(type default)
			)
			(layer "F.SilkS")
		)
		(fp_line
			(start 0.7874 -0.4064)
			(end 0.7874 0.4064)
			(stroke
				(width 0.1524)
				(type default)
			)
			(layer "F.SilkS")
		)
		(fp_line
			(start 0.7874 0.4064)
			(end -0.7874 0.4064)
			(stroke
				(width 0.1524)
				(type default)
			)
			(layer "F.SilkS")
		)
		(fp_line
			(start -0.67945 -0.305054)
			(end -0.12065 -0.305054)
			(stroke
				(width 0.1)
				(type default)
			)
			(layer "F.Fab")
		)
		(fp_line
			(start -0.67945 0.3048)
			(end -0.67945 -0.305054)
			(stroke
				(width 0.1)
				(type default)
			)
			(layer "F.Fab")
		)
		(fp_line
			(start -0.12065 -0.305054)
			(end -0.12065 -0.2794)
			(stroke
				(width 0.1)
				(type default)
			)
			(layer "F.Fab")
		)
		(fp_line
			(start -0.12065 -0.2794)
			(end 0.12065 -0.2794)
			(stroke
				(width 0.1)
				(type default)
			)
			(layer "F.Fab")
		)
		(fp_line
			(start -0.12065 0.2794)
			(end -0.12065 0.3048)
			(stroke
				(width 0.1)
				(type default)
			)
			(layer "F.Fab")
		)
		(fp_line
			(start -0.12065 0.3048)
			(end -0.67945 0.3048)
			(stroke
				(width 0.1)
				(type default)
			)
			(layer "F.Fab")
		)
		(fp_line
			(start 0.120396 0.2794)
			(end -0.12065 0.2794)
			(stroke
				(width 0.1)
				(type default)
			)
			(layer "F.Fab")
		)
		(fp_line
			(start 0.120396 0.3048)
			(end 0.120396 0.2794)
			(stroke
				(width 0.1)
				(type default)
			)
			(layer "F.Fab")
		)
		(fp_line
			(start 0.12065 -0.3048)
			(end 0.67945 -0.3048)
			(stroke
				(width 0.1)
				(type default)
			)
			(layer "F.Fab")
		)
		(fp_line
			(start 0.12065 -0.2794)
			(end 0.12065 -0.3048)
			(stroke
				(width 0.1)
				(type default)
			)
			(layer "F.Fab")
		)
		(fp_line
			(start 0.67945 -0.3048)
			(end 0.67945 0.3048)
			(stroke
				(width 0.1)
				(type default)
			)
			(layer "F.Fab")
		)
		(fp_line
			(start 0.67945 0.3048)
			(end 0.120396 0.3048)
			(stroke
				(width 0.1)
				(type default)
			)
			(layer "F.Fab")
		)
		(pad "1" smd circle
			(at -0.40005 0)
			(size 0 0)
			(layers "F.Cu" "F.Mask" "F.Paste")
			(net "SMB_INA230_3V3AUX_SCL_R")
		)
		(pad "2" smd circle
			(at 0.40005 0)
			(size 0 0)
			(layers "F.Cu" "F.Mask" "F.Paste")
			(net "SMB_INA230_3V3AUX_SCL")
		)
	)
)
